# BASEBOARD_FAB2 (Tioga Pass) — schematic netlist excerpt (pin names and nets, part order shuffled) for the footprints in the layout excerpt that follows; sources: Cadence DE-HDL packaged netlist, KiCad conversion of Wiwynn_Tioga_Pass_MB.brd

R8D31  RES  4.75K 1% CHIP  pkg 0402  page 89 : A = P3V3_STBY ; B = IRQ_DIMM_SAVE_LVT3_N
C9N16  CAP  0.22UF 16V 10% X7R  pkg 0402  page 182 : A = P3E_CPU1_PE3_MP_C_TXN<12> ; B = P3E_CPU1_PE3_MP_TXN<12>

(kicad_pcb
	(version 20260206)
	(generator "pcbnew")
	(generator_version "10.0")
	(general
		(thickness 1.6)
		(legacy_teardrops no)
	)
	(paper "A4")
	(title_block
		(title "Wiwynn_Tioga_Pass_MB.brd")
		(comment 1 "Tioga Pass / footprints 4510-4512 of 4770")
	)
	(layers
		(0 "F.Cu" signal "TOP")
		(4 "In1.Cu" signal "L2GND")
		(6 "In2.Cu" signal "L3")
		(8 "In3.Cu" signal "L4GND")
		(10 "In4.Cu" signal "L5")
		(12 "In5.Cu" signal "L6GND")
		(14 "In6.Cu" signal "L7VCC")
		(16 "In7.Cu" signal "L8VCC")
		(18 "In8.Cu" signal "L9GND")
		(20 "In9.Cu" signal "L10")
		(22 "In10.Cu" signal "L11GND")
		(24 "In11.Cu" signal "L12")
		(26 "In12.Cu" signal "L13GND")
		(2 "B.Cu" signal "BOTTOM")
		(9 "F.Adhes" user "F.Adhesive")
		(11 "B.Adhes" user "B.Adhesive")
		(13 "F.Paste" user "Package Geometry/Pastemask Top")
		(15 "B.Paste" user "Package Geometry/Pastemask Bottom")
		(5 "F.SilkS" user "Ref Des/Silkscreen Top")
		(7 "B.SilkS" user "Ref Des/Silkscreen Bottom")
		(1 "F.Mask" user "Board Geometry/Soldermask Top")
		(3 "B.Mask" user "Board Geometry/Soldermask Bottom")
		(17 "Dwgs.User" user "User.Drawings")
		(19 "Cmts.User" user "User.Comments")
		(21 "Eco1.User" user "User.Eco1")
		(23 "Eco2.User" user "User.Eco2")
		(25 "Edge.Cuts" user "Board Geometry/Outline")
		(27 "Margin" user)
		(31 "F.CrtYd" user "Package Geometry/Place Bound Top")
		(29 "B.CrtYd" user "Package Geometry/Place Bound Bottom")
		(35 "F.Fab" user "Ref Des/Assembly Top")
		(33 "B.Fab" user "Ref Des/Assembly Bottom")
	)
	(footprint ""
		(layer "B.Cu")
		(at 186.69 -99.695)
		(property "Reference" ""
			(at 0 0 0)
			(layer "B.SilkS")
			(hide yes)
			(effects
				(font
					(size 1.27 1.27)
				)
				(justify mirror)
			)
		)
		(property "Value" ""
			(at 0 0 0)
			(layer "B.Fab")
			(effects
				(font
					(size 1.27 1.27)
				)
				(justify mirror)
			)
		)
		(duplicate_pad_numbers_are_jumpers no)
		(fp_poly
			(pts
				(arc
					(start 2.032 0)
					(mid -2.032 0)
					(end 2.032 0)
				)
			)
			(stroke
				(width 0)
				(type default)
			)
			(fill no)
			(layer "B.CrtYd")
		)
		(pad "1" smd circle
			(at 0 0 180)
			(size 1.016 1.016)
			(layers "B.Cu" "B.Mask" "B.Paste")
			(net "Net_392")
		)
		(zone
			(layers "F.Cu" "B.Cu" "In1.Cu" "In2.Cu" "In3.Cu" "In4.Cu" "In5.Cu" "In6.Cu"
				"In7.Cu" "In8.Cu" "In9.Cu" "In10.Cu" "In11.Cu" "In12.Cu"
			)
			(hatch none 0.5)
			(connect_pads
				(clearance 0)
			)
			(min_thickness 0.25)
			(keepout
				(tracks allowed)
				(vias not_allowed)
				(pads allowed)
				(copperpour not_allowed)
				(footprints allowed)
			)
			(placement
				(enabled no)
				(sheetname "")
			)
			(fill
				(thermal_gap 0.5)
				(thermal_bridge_width 0.5)
				(island_removal_mode 0)
			)
			(polygon
				(pts
					(arc
						(start 188.214 -99.695)
						(mid 185.166 -99.695)
						(end 188.214 -99.695)
					)
				)
			)
		)
		(zone
			(layer "B.Cu")
			(hatch none 0.5)
			(connect_pads
				(clearance 0)
			)
			(min_thickness 0.25)
			(keepout
				(tracks not_allowed)
				(vias allowed)
				(pads allowed)
				(copperpour not_allowed)
				(footprints allowed)
			)
			(placement
				(enabled no)
				(sheetname "")
			)
			(fill
				(thermal_gap 0.5)
				(thermal_bridge_width 0.5)
				(island_removal_mode 0)
			)
			(polygon
				(pts
					(arc
						(start 188.214 -99.695)
						(mid 185.166 -99.695)
						(end 188.214 -99.695)
					)
				)
			)
		)
	)
	(footprint ""
		(layer "B.Cu")
		(at 310.307228 -28.944824)
		(property "Reference" "R8D31"
			(at 0 0 0)
			(layer "B.SilkS")
			(hide yes)
			(effects
				(font
					(size 1.27 1.27)
				)
				(justify mirror)
			)
		)
		(property "Value" ""
			(at 0 0 0)
			(layer "B.Fab")
			(effects
				(font
					(size 1.27 1.27)
				)
				(justify mirror)
			)
		)
		(duplicate_pad_numbers_are_jumpers no)
		(fp_poly
			(pts
				(xy 0.2794 -0.1016) (xy -0.2794 -0.1016) (xy -0.2794 0.9906) (xy 0.2794 0.9906)
			)
			(stroke
				(width 0)
				(type default)
			)
			(fill no)
			(layer "B.CrtYd")
		)
		(fp_line
			(start -0.2794 -0.1016)
			(end 0.2794 -0.1016)
			(stroke
				(width 0.1)
				(type default)
			)
			(layer "B.Fab")
		)
		(fp_line
			(start -0.2794 0.9906)
			(end -0.2794 -0.1016)
			(stroke
				(width 0.1)
				(type default)
			)
			(layer "B.Fab")
		)
		(fp_line
			(start 0.2794 -0.1016)
			(end 0.2794 0.9906)
			(stroke
				(width 0.1)
				(type default)
			)
			(layer "B.Fab")
		)
		(fp_line
			(start 0.2794 0.9906)
			(end -0.2794 0.9906)
			(stroke
				(width 0.1)
				(type default)
			)
			(layer "B.Fab")
		)
		(pad "1" smd rect
			(at 0 0 180)
			(size 0.508 0.508)
			(layers "B.Cu" "B.Mask" "B.Paste")
			(net "P3V3_STBY")
		)
		(pad "2" smd rect
			(at 0 0.889 180)
			(size 0.508 0.508)
			(layers "B.Cu" "B.Mask" "B.Paste")
			(net "IRQ_DIMM_SAVE_LVT3_N")
		)
		(zone
			(layer "B.Cu")
			(hatch none 0.5)
			(connect_pads
				(clearance 0)
			)
			(min_thickness 0.25)
			(keepout
				(tracks allowed)
				(vias not_allowed)
				(pads allowed)
				(copperpour not_allowed)
				(footprints allowed)
			)
			(placement
				(enabled no)
				(sheetname "")
			)
			(fill
				(thermal_gap 0.5)
				(thermal_bridge_width 0.5)
				(island_removal_mode 0)
			)
			(polygon
				(pts
					(xy 310.561228 -28.690824) (xy 310.053228 -28.690824) (xy 310.053228 -28.309824) (xy 310.561228 -28.309824)
				)
			)
		)
		(zone
			(layer "B.Cu")
			(hatch none 0.5)
			(connect_pads
				(clearance 0)
			)
			(min_thickness 0.25)
			(keepout
				(tracks not_allowed)
				(vias allowed)
				(pads allowed)
				(copperpour not_allowed)
				(footprints allowed)
			)
			(placement
				(enabled no)
				(sheetname "")
			)
			(fill
				(thermal_gap 0.5)
				(thermal_bridge_width 0.5)
				(island_removal_mode 0)
			)
			(polygon
				(pts
					(xy 310.561228 -28.309824) (xy 310.053228 -28.309824) (xy 310.053228 -28.690824) (xy 310.561228 -28.690824)
				)
			)
		)
	)
	(footprint ""
		(layer "B.Cu")
		(at 13.11402 -99.57308 90)
		(property "Reference" "C9N16"
			(at 0 0 90)
			(layer "B.SilkS")
			(hide yes)
			(effects
				(font
					(size 1.27 1.27)
				)
				(justify mirror)
			)
		)
		(property "Value" ""
			(at 0 0 90)
			(layer "B.Fab")
			(effects
				(font
					(size 1.27 1.27)
				)
				(justify mirror)
			)
		)
		(duplicate_pad_numbers_are_jumpers no)
		(fp_poly
			(pts
				(xy -0.3048 -0.1016) (xy -0.3048 0.9906) (xy 0.3048 0.9906) (xy 0.3048 -0.1016)
			)
			(stroke
				(width 0)
				(type default)
			)
			(fill no)
			(layer "B.CrtYd")
		)
		(fp_line
			(start 0.3048 -0.1016)
			(end 0.3048 0.9906)
			(stroke
				(width 0.1)
				(type default)
			)
			(layer "B.Fab")
		)
		(fp_line
			(start -0.3048 -0.1016)
			(end 0.3048 -0.1016)
			(stroke
				(width 0.1)
				(type default)
			)
			(layer "B.Fab")
		)
		(fp_line
			(start 0.3048 0.9906)
			(end -0.3048 0.9906)
			(stroke
				(width 0.1)
				(type default)
			)
			(layer "B.Fab")
		)
		(fp_line
			(start -0.3048 0.9906)
			(end -0.3048 -0.1016)
			(stroke
				(width 0.1)
				(type default)
			)
			(layer "B.Fab")
		)
		(pad "1" smd rect
			(at 0 0 270)
			(size 0.508 0.508)
			(layers "B.Cu" "B.Mask" "B.Paste")
			(net "P3E_CPU1_PE3_MP_C_TXN<12>")
		)
		(pad "2" smd rect
			(at 0 0.889 270)
			(size 0.508 0.508)
			(layers "B.Cu" "B.Mask" "B.Paste")
			(net "P3E_CPU1_PE3_MP_TXN<12>")
		)
		(zone
			(layer "B.Cu")
			(hatch none 0.5)
			(connect_pads
				(clearance 0)
			)
			(min_thickness 0.25)
			(keepout
				(tracks allowed)
				(vias not_allowed)
				(pads allowed)
				(copperpour not_allowed)
				(footprints allowed)
			)
			(placement
				(enabled no)
				(sheetname "")
			)
			(fill
				(thermal_gap 0.5)
				(thermal_bridge_width 0.5)
				(island_removal_mode 0)
			)
			(polygon
				(pts
					(xy 13.36802 -99.82708) (xy 13.36802 -99.31908) (xy 13.74902 -99.31908) (xy 13.74902 -99.82708)
				)
			)
		)
		(zone
			(layer "B.Cu")
			(hatch none 0.5)
			(connect_pads
				(clearance 0)
			)
			(min_thickness 0.25)
			(keepout
				(tracks not_allowed)
				(vias allowed)
				(pads allowed)
				(copperpour not_allowed)
				(footprints allowed)
			)
			(placement
				(enabled no)
				(sheetname "")
			)
			(fill
				(thermal_gap 0.5)
				(thermal_bridge_width 0.5)
				(island_removal_mode 0)
			)
			(polygon
				(pts
					(xy 13.74902 -99.82708) (xy 13.74902 -99.31908) (xy 13.36802 -99.31908) (xy 13.36802 -99.82708)
				)
			)
		)
	)
)
